(kicad_pcb
	(version 20260206)
	(generator "pcbnew")
	(generator_version "10.0")
	(general
		(thickness 1.6)
		(legacy_teardrops no)
	)
	(paper "A4")
	(title_block
		(title "03242023_DA0F0TMBIJ0_F0T_Motherboard_J_brd_V01_OCP.brd")
		(comment 1 "Grand Teton / footprints 917-924 of 6105")
	)
	(layers
		(0 "F.Cu" signal "TOP")
		(4 "In1.Cu" signal "GND")
		(6 "In2.Cu" signal "IN1")
		(8 "In3.Cu" signal "GND1")
		(10 "In4.Cu" signal "IN2")
		(12 "In5.Cu" signal "GND2")
		(14 "In6.Cu" signal "IN3")
		(16 "In7.Cu" signal "GND3")
		(18 "In8.Cu" signal "VCC")
		(20 "In9.Cu" signal "VCC1")
		(22 "In10.Cu" signal "GND4")
		(24 "In11.Cu" signal "IN4")
		(26 "In12.Cu" signal "GND5")
		(28 "In13.Cu" signal "IN5")
		(30 "In14.Cu" signal "GND6")
		(32 "In15.Cu" signal "IN6")
		(34 "In16.Cu" signal "GND7")
		(2 "B.Cu" signal "BOTTOM")
		(9 "F.Adhes" user "F.Adhesive")
		(11 "B.Adhes" user "B.Adhesive")
		(13 "F.Paste" user "Package Geometry/Pastemask Top")
		(15 "B.Paste" user "Package Geometry/Pastemask Bottom")
		(5 "F.SilkS" user "Ref Des/Silkscreen Top")
		(7 "B.SilkS" user "Ref Des/Silkscreen Bottom")
		(1 "F.Mask" user "Board Geometry/Soldermask Top")
		(3 "B.Mask" user "Board Geometry/Soldermask Bottom")
		(17 "Dwgs.User" user "User.Drawings")
		(19 "Cmts.User" user "User.Comments")
		(21 "Eco1.User" user "User.Eco1")
		(23 "Eco2.User" user "User.Eco2")
		(25 "Edge.Cuts" user "Board Geometry/Outline")
		(27 "Margin" user)
		(31 "F.CrtYd" user "Package Geometry/Place Bound Top")
		(29 "B.CrtYd" user "Package Geometry/Place Bound Bottom")
		(35 "F.Fab" user "Ref Des/Assembly Top")
		(33 "B.Fab" user "Ref Des/Assembly Bottom")
	)
	(footprint ""
		(layer "F.Cu")
		(at 166.77894 -28.044648)
		(property "Reference" "U307"
			(at 1.03632 2.521712 0)
			(unlocked yes)
			(layer "F.SilkS")
			(effects
				(font
					(size 0.7874 0.5842)
					(thickness 0.1524)
				)
			)
		)
		(property "Value" ""
			(at 0 0 0)
			(layer "F.Fab")
			(effects
				(font
					(size 1.27 1.27)
				)
			)
		)
		(duplicate_pad_numbers_are_jumpers no)
		(fp_line
			(start -1.949958 -1.610106)
			(end 1.949958 -1.610106)
			(stroke
				(width 0.1524)
				(type default)
			)
			(layer "F.SilkS")
		)
		(fp_line
			(start -1.949958 1.610106)
			(end -1.949958 -1.610106)
			(stroke
				(width 0.1524)
				(type default)
			)
			(layer "F.SilkS")
		)
		(fp_line
			(start 1.949958 -1.560068)
			(end 1.949958 1.610106)
			(stroke
				(width 0.1524)
				(type default)
			)
			(layer "F.SilkS")
		)
		(fp_line
			(start 1.949958 1.610106)
			(end -1.949958 1.610106)
			(stroke
				(width 0.1524)
				(type default)
			)
			(layer "F.SilkS")
		)
		(fp_line
			(start -0.750062 -1.560068)
			(end 0.750062 -1.560068)
			(stroke
				(width 0.1)
				(type default)
			)
			(layer "F.Fab")
		)
		(fp_line
			(start -0.750062 1.560068)
			(end -0.750062 -1.560068)
			(stroke
				(width 0.1)
				(type default)
			)
			(layer "F.Fab")
		)
		(fp_line
			(start 0.750062 -1.560068)
			(end 0.750062 1.560068)
			(stroke
				(width 0.1)
				(type default)
			)
			(layer "F.Fab")
		)
		(fp_line
			(start 0.750062 1.560068)
			(end -0.750062 1.560068)
			(stroke
				(width 0.1)
				(type default)
			)
			(layer "F.Fab")
		)
		(pad "D" smd rect
			(at 1.100074 0 270)
			(size 1.016 1.4224)
			(layers "F.Cu" "F.Mask" "F.Paste")
			(net "FM_LPC_ESPI_SEL")
		)
		(pad "G" smd rect
			(at -1.100074 -0.94996 270)
			(size 1.016 1.4224)
			(layers "F.Cu" "F.Mask" "F.Paste")
			(net "FM_ESPI_PLD_R_EN_BUF_R")
		)
		(pad "S" smd rect
			(at -1.100074 0.94996 270)
			(size 1.016 1.4224)
			(layers "F.Cu" "F.Mask" "F.Paste")
			(net "GND")
		)
	)
	(footprint ""
		(layer "F.Cu")
		(at 217.12428 -108.321348 90)
		(property "Reference" "U89"
			(at -0.264922 3.129788 0)
			(unlocked yes)
			(layer "F.SilkS")
			(effects
				(font
					(size 0.7874 0.5842)
					(thickness 0.1524)
				)
			)
		)
		(property "Value" ""
			(at 0 0 90)
			(layer "F.Fab")
			(effects
				(font
					(size 1.27 1.27)
				)
			)
		)
		(duplicate_pad_numbers_are_jumpers no)
		(fp_line
			(start -1.949958 -1.610106)
			(end 1.949958 -1.610106)
			(stroke
				(width 0.1524)
				(type default)
			)
			(layer "F.SilkS")
		)
		(fp_line
			(start 1.949958 -1.560068)
			(end 1.949958 1.610106)
			(stroke
				(width 0.1524)
				(type default)
			)
			(layer "F.SilkS")
		)
		(fp_line
			(start 1.949958 1.610106)
			(end -1.949958 1.610106)
			(stroke
				(width 0.1524)
				(type default)
			)
			(layer "F.SilkS")
		)
		(fp_line
			(start -1.949958 1.610106)
			(end -1.949958 -1.610106)
			(stroke
				(width 0.1524)
				(type default)
			)
			(layer "F.SilkS")
		)
		(fp_line
			(start 0.750062 -1.560068)
			(end 0.750062 1.560068)
			(stroke
				(width 0.1)
				(type default)
			)
			(layer "F.Fab")
		)
		(fp_line
			(start -0.750062 -1.560068)
			(end 0.750062 -1.560068)
			(stroke
				(width 0.1)
				(type default)
			)
			(layer "F.Fab")
		)
		(fp_line
			(start 0.750062 1.560068)
			(end -0.750062 1.560068)
			(stroke
				(width 0.1)
				(type default)
			)
			(layer "F.Fab")
		)
		(fp_line
			(start -0.750062 1.560068)
			(end -0.750062 -1.560068)
			(stroke
				(width 0.1)
				(type default)
			)
			(layer "F.Fab")
		)
		(pad "D" smd rect
			(at 1.100074 0)
			(size 1.016 1.4224)
			(layers "F.Cu" "F.Mask" "F.Paste")
			(net "FM_PLD_HEARTBEAT_LVC3_D")
		)
		(pad "G" smd rect
			(at -1.100074 -0.94996)
			(size 1.016 1.4224)
			(layers "F.Cu" "F.Mask" "F.Paste")
			(net "FM_PLD_HEARTBEAT_LVC3")
		)
		(pad "S" smd rect
			(at -1.100074 0.94996)
			(size 1.016 1.4224)
			(layers "F.Cu" "F.Mask" "F.Paste")
			(net "GND")
		)
	)
	(footprint ""
		(layer "F.Cu")
		(at 364.50143 -249.320304 -90)
		(property "Reference" "C969"
			(at 0 0 270)
			(layer "F.SilkS")
			(hide yes)
			(effects
				(font
					(size 1.27 1.27)
				)
			)
		)
		(property "Value" ""
			(at 0 0 270)
			(layer "F.Fab")
			(effects
				(font
					(size 1.27 1.27)
				)
			)
		)
		(duplicate_pad_numbers_are_jumpers no)
		(fp_line
			(start -0.7874 0.4064)
			(end -0.7874 -0.4064)
			(stroke
				(width 0.1524)
				(type default)
			)
			(layer "F.SilkS")
		)
		(fp_line
			(start 0.7874 0.4064)
			(end -0.7874 0.4064)
			(stroke
				(width 0.1524)
				(type default)
			)
			(layer "F.SilkS")
		)
		(fp_line
			(start -0.7874 -0.4064)
			(end 0.7874 -0.4064)
			(stroke
				(width 0.1524)
				(type default)
			)
			(layer "F.SilkS")
		)
		(fp_line
			(start 0.7874 -0.4064)
			(end 0.7874 0.4064)
			(stroke
				(width 0.1524)
				(type default)
			)
			(layer "F.SilkS")
		)
		(fp_line
			(start -0.67945 0.3048)
			(end -0.67945 -0.305054)
			(stroke
				(width 0.1)
				(type default)
			)
			(layer "F.Fab")
		)
		(fp_line
			(start -0.12065 0.3048)
			(end -0.67945 0.3048)
			(stroke
				(width 0.1)
				(type default)
			)
			(layer "F.Fab")
		)
		(fp_line
			(start 0.120396 0.3048)
			(end 0.120396 0.2794)
			(stroke
				(width 0.1)
				(type default)
			)
			(layer "F.Fab")
		)
		(fp_line
			(start 0.67945 0.3048)
			(end 0.120396 0.3048)
			(stroke
				(width 0.1)
				(type default)
			)
			(layer "F.Fab")
		)
		(fp_line
			(start -0.12065 0.2794)
			(end -0.12065 0.3048)
			(stroke
				(width 0.1)
				(type default)
			)
			(layer "F.Fab")
		)
		(fp_line
			(start 0.120396 0.2794)
			(end -0.12065 0.2794)
			(stroke
				(width 0.1)
				(type default)
			)
			(layer "F.Fab")
		)
		(fp_line
			(start -0.12065 -0.2794)
			(end 0.12065 -0.2794)
			(stroke
				(width 0.1)
				(type default)
			)
			(layer "F.Fab")
		)
		(fp_line
			(start 0.12065 -0.2794)
			(end 0.12065 -0.3048)
			(stroke
				(width 0.1)
				(type default)
			)
			(layer "F.Fab")
		)
		(fp_line
			(start 0.12065 -0.3048)
			(end 0.67945 -0.3048)
			(stroke
				(width 0.1)
				(type default)
			)
			(layer "F.Fab")
		)
		(fp_line
			(start 0.67945 -0.3048)
			(end 0.67945 0.3048)
			(stroke
				(width 0.1)
				(type default)
			)
			(layer "F.Fab")
		)
		(fp_line
			(start -0.67945 -0.305054)
			(end -0.12065 -0.305054)
			(stroke
				(width 0.1)
				(type default)
			)
			(layer "F.Fab")
		)
		(fp_line
			(start -0.12065 -0.305054)
			(end -0.12065 -0.2794)
			(stroke
				(width 0.1)
				(type default)
			)
			(layer "F.Fab")
		)
		(pad "1" smd circle
			(at -0.40005 0 270)
			(size 0 0)
			(layers "F.Cu" "F.Mask" "F.Paste")
			(net "PVCCIN_CPU0")
		)
		(pad "2" smd circle
			(at 0.40005 0 270)
			(size 0 0)
			(layers "F.Cu" "F.Mask" "F.Paste")
			(net "GND")
		)
	)
	(footprint ""
		(layer "F.Cu")
		(at 250.317 -38.048946 -90)
		(property "Reference" "R3972"
			(at 0 0 270)
			(layer "F.SilkS")
			(hide yes)
			(effects
				(font
					(size 1.27 1.27)
				)
			)
		)
		(property "Value" ""
			(at 0 0 270)
			(layer "F.Fab")
			(effects
				(font
					(size 1.27 1.27)
				)
			)
		)
		(duplicate_pad_numbers_are_jumpers no)
		(fp_line
			(start -0.7874 0.4064)
			(end -0.7874 -0.4064)
			(stroke
				(width 0.1524)
				(type default)
			)
			(layer "F.SilkS")
		)
		(fp_line
			(start 0.7874 0.4064)
			(end -0.7874 0.4064)
			(stroke
				(width 0.1524)
				(type default)
			)
			(layer "F.SilkS")
		)
		(fp_line
			(start -0.7874 -0.4064)
			(end 0.7874 -0.4064)
			(stroke
				(width 0.1524)
				(type default)
			)
			(layer "F.SilkS")
		)
		(fp_line
			(start 0.7874 -0.4064)
			(end 0.7874 0.4064)
			(stroke
				(width 0.1524)
				(type default)
			)
			(layer "F.SilkS")
		)
		(fp_line
			(start -0.67945 0.3048)
			(end -0.67945 -0.305054)
			(stroke
				(width 0.1)
				(type default)
			)
			(layer "F.Fab")
		)
		(fp_line
			(start -0.12065 0.3048)
			(end -0.67945 0.3048)
			(stroke
				(width 0.1)
				(type default)
			)
			(layer "F.Fab")
		)
		(fp_line
			(start 0.120396 0.3048)
			(end 0.120396 0.2794)
			(stroke
				(width 0.1)
				(type default)
			)
			(layer "F.Fab")
		)
		(fp_line
			(start 0.67945 0.3048)
			(end 0.120396 0.3048)
			(stroke
				(width 0.1)
				(type default)
			)
			(layer "F.Fab")
		)
		(fp_line
			(start -0.12065 0.2794)
			(end -0.12065 0.3048)
			(stroke
				(width 0.1)
				(type default)
			)
			(layer "F.Fab")
		)
		(fp_line
			(start 0.120396 0.2794)
			(end -0.12065 0.2794)
			(stroke
				(width 0.1)
				(type default)
			)
			(layer "F.Fab")
		)
		(fp_line
			(start -0.12065 -0.2794)
			(end 0.12065 -0.2794)
			(stroke
				(width 0.1)
				(type default)
			)
			(layer "F.Fab")
		)
		(fp_line
			(start 0.12065 -0.2794)
			(end 0.12065 -0.3048)
			(stroke
				(width 0.1)
				(type default)
			)
			(layer "F.Fab")
		)
		(fp_line
			(start 0.12065 -0.3048)
			(end 0.67945 -0.3048)
			(stroke
				(width 0.1)
				(type default)
			)
			(layer "F.Fab")
		)
		(fp_line
			(start 0.67945 -0.3048)
			(end 0.67945 0.3048)
			(stroke
				(width 0.1)
				(type default)
			)
			(layer "F.Fab")
		)
		(fp_line
			(start -0.67945 -0.305054)
			(end -0.12065 -0.305054)
			(stroke
				(width 0.1)
				(type default)
			)
			(layer "F.Fab")
		)
		(fp_line
			(start -0.12065 -0.305054)
			(end -0.12065 -0.2794)
			(stroke
				(width 0.1)
				(type default)
			)
			(layer "F.Fab")
		)
		(pad "1" smd circle
			(at -0.40005 0 270)
			(size 0 0)
			(layers "F.Cu" "F.Mask" "F.Paste")
			(net "P12V_E1S_PWRGD_0")
		)
		(pad "2" smd circle
			(at 0.40005 0 270)
			(size 0 0)
			(layers "F.Cu" "F.Mask" "F.Paste")
			(net "HP_LVC3_E1S_0_HSC_PWRGD")
		)
	)
	(footprint ""
		(layer "F.Cu")
		(at 453.054212 -23.603458)
		(property "Reference" "PC4056"
			(at 0 0 0)
			(layer "F.SilkS")
			(hide yes)
			(effects
				(font
					(size 1.27 1.27)
				)
			)
		)
		(property "Value" ""
			(at 0 0 0)
			(layer "F.Fab")
			(effects
				(font
					(size 1.27 1.27)
				)
			)
		)
		(duplicate_pad_numbers_are_jumpers no)
		(fp_line
			(start -0.7874 -0.4064)
			(end 0.7874 -0.4064)
			(stroke
				(width 0.1524)
				(type default)
			)
			(layer "F.SilkS")
		)
		(fp_line
			(start -0.7874 0.4064)
			(end -0.7874 -0.4064)
			(stroke
				(width 0.1524)
				(type default)
			)
			(layer "F.SilkS")
		)
		(fp_line
			(start 0.7874 -0.4064)
			(end 0.7874 0.4064)
			(stroke
				(width 0.1524)
				(type default)
			)
			(layer "F.SilkS")
		)
		(fp_line
			(start 0.7874 0.4064)
			(end -0.7874 0.4064)
			(stroke
				(width 0.1524)
				(type default)
			)
			(layer "F.SilkS")
		)
		(fp_line
			(start -0.67945 -0.305054)
			(end -0.12065 -0.305054)
			(stroke
				(width 0.1)
				(type default)
			)
			(layer "F.Fab")
		)
		(fp_line
			(start -0.67945 0.3048)
			(end -0.67945 -0.305054)
			(stroke
				(width 0.1)
				(type default)
			)
			(layer "F.Fab")
		)
		(fp_line
			(start -0.12065 -0.305054)
			(end -0.12065 -0.2794)
			(stroke
				(width 0.1)
				(type default)
			)
			(layer "F.Fab")
		)
		(fp_line
			(start -0.12065 -0.2794)
			(end 0.12065 -0.2794)
			(stroke
				(width 0.1)
				(type default)
			)
			(layer "F.Fab")
		)
		(fp_line
			(start -0.12065 0.2794)
			(end -0.12065 0.3048)
			(stroke
				(width 0.1)
				(type default)
			)
			(layer "F.Fab")
		)
		(fp_line
			(start -0.12065 0.3048)
			(end -0.67945 0.3048)
			(stroke
				(width 0.1)
				(type default)
			)
			(layer "F.Fab")
		)
		(fp_line
			(start 0.120396 0.2794)
			(end -0.12065 0.2794)
			(stroke
				(width 0.1)
				(type default)
			)
			(layer "F.Fab")
		)
		(fp_line
			(start 0.120396 0.3048)
			(end 0.120396 0.2794)
			(stroke
				(width 0.1)
				(type default)
			)
			(layer "F.Fab")
		)
		(fp_line
			(start 0.12065 -0.3048)
			(end 0.67945 -0.3048)
			(stroke
				(width 0.1)
				(type default)
			)
			(layer "F.Fab")
		)
		(fp_line
			(start 0.12065 -0.2794)
			(end 0.12065 -0.3048)
			(stroke
				(width 0.1)
				(type default)
			)
			(layer "F.Fab")
		)
		(fp_line
			(start 0.67945 -0.3048)
			(end 0.67945 0.3048)
			(stroke
				(width 0.1)
				(type default)
			)
			(layer "F.Fab")
		)
		(fp_line
			(start 0.67945 0.3048)
			(end 0.120396 0.3048)
			(stroke
				(width 0.1)
				(type default)
			)
			(layer "F.Fab")
		)
		(pad "1" smd circle
			(at -0.40005 0)
			(size 0 0)
			(layers "F.Cu" "F.Mask" "F.Paste")
			(net "P12V_OCP_GATE_1")
		)
		(pad "2" smd circle
			(at 0.40005 0)
			(size 0 0)
			(layers "F.Cu" "F.Mask" "F.Paste")
			(net "GND")
		)
	)
	(footprint ""
		(layer "F.Cu")
		(at 332.870048 -408.517344 -90)
		(property "Reference" "C920"
			(at 0 0 270)
			(layer "F.SilkS")
			(hide yes)
			(effects
				(font
					(size 1.27 1.27)
				)
			)
		)
		(property "Value" ""
			(at 0 0 270)
			(layer "F.Fab")
			(effects
				(font
					(size 1.27 1.27)
				)
			)
		)
		(duplicate_pad_numbers_are_jumpers no)
		(fp_line
			(start -0.299974 0.150114)
			(end -0.299974 -0.150114)
			(stroke
				(width 0.1)
				(type default)
			)
			(layer "F.Fab")
		)
		(fp_line
			(start 0.299974 0.150114)
			(end -0.299974 0.150114)
			(stroke
				(width 0.1)
				(type default)
			)
			(layer "F.Fab")
		)
		(fp_line
			(start -0.299974 -0.150114)
			(end 0.299974 -0.150114)
			(stroke
				(width 0.1)
				(type default)
			)
			(layer "F.Fab")
		)
		(fp_line
			(start 0.299974 -0.150114)
			(end 0.299974 0.150114)
			(stroke
				(width 0.1)
				(type default)
			)
			(layer "F.Fab")
		)
		(pad "1" smd rect
			(at -0.2667 0 270)
			(size 0.3048 0.381)
			(layers "F.Cu" "F.Mask" "F.Paste")
			(net "P5E_CPU0_PE0_TX_C_DN<6>")
		)
		(pad "2" smd rect
			(at 0.2667 0 270)
			(size 0.3048 0.381)
			(layers "F.Cu" "F.Mask" "F.Paste")
			(net "P5E_CPU0_PE0_TX_DN<6>")
		)
	)
	(footprint ""
		(layer "F.Cu")
		(at 218.12758 -131.973828)
		(property "Reference" "C1315"
			(at 0 0 0)
			(layer "F.SilkS")
			(hide yes)
			(effects
				(font
					(size 1.27 1.27)
				)
			)
		)
		(property "Value" ""
			(at 0 0 0)
			(layer "F.Fab")
			(effects
				(font
					(size 1.27 1.27)
				)
			)
		)
		(duplicate_pad_numbers_are_jumpers no)
		(fp_line
			(start -0.7874 -0.4064)
			(end 0.7874 -0.4064)
			(stroke
				(width 0.1524)
				(type default)
			)
			(layer "F.SilkS")
		)
		(fp_line
			(start -0.7874 0.4064)
			(end -0.7874 -0.4064)
			(stroke
				(width 0.1524)
				(type default)
			)
			(layer "F.SilkS")
		)
		(fp_line
			(start 0.7874 -0.4064)
			(end 0.7874 0.4064)
			(stroke
				(width 0.1524)
				(type default)
			)
			(layer "F.SilkS")
		)
		(fp_line
			(start 0.7874 0.4064)
			(end -0.7874 0.4064)
			(stroke
				(width 0.1524)
				(type default)
			)
			(layer "F.SilkS")
		)
		(fp_line
			(start -0.67945 -0.305054)
			(end -0.12065 -0.305054)
			(stroke
				(width 0.1)
				(type default)
			)
			(layer "F.Fab")
		)
		(fp_line
			(start -0.67945 0.3048)
			(end -0.67945 -0.305054)
			(stroke
				(width 0.1)
				(type default)
			)
			(layer "F.Fab")
		)
		(fp_line
			(start -0.12065 -0.305054)
			(end -0.12065 -0.2794)
			(stroke
				(width 0.1)
				(type default)
			)
			(layer "F.Fab")
		)
		(fp_line
			(start -0.12065 -0.2794)
			(end 0.12065 -0.2794)
			(stroke
				(width 0.1)
				(type default)
			)
			(layer "F.Fab")
		)
		(fp_line
			(start -0.12065 0.2794)
			(end -0.12065 0.3048)
			(stroke
				(width 0.1)
				(type default)
			)
			(layer "F.Fab")
		)
		(fp_line
			(start -0.12065 0.3048)
			(end -0.67945 0.3048)
			(stroke
				(width 0.1)
				(type default)
			)
			(layer "F.Fab")
		)
		(fp_line
			(start 0.120396 0.2794)
			(end -0.12065 0.2794)
			(stroke
				(width 0.1)
				(type default)
			)
			(layer "F.Fab")
		)
		(fp_line
			(start 0.120396 0.3048)
			(end 0.120396 0.2794)
			(stroke
				(width 0.1)
				(type default)
			)
			(layer "F.Fab")
		)
		(fp_line
			(start 0.12065 -0.3048)
			(end 0.67945 -0.3048)
			(stroke
				(width 0.1)
				(type default)
			)
			(layer "F.Fab")
		)
		(fp_line
			(start 0.12065 -0.2794)
			(end 0.12065 -0.3048)
			(stroke
				(width 0.1)
				(type default)
			)
			(layer "F.Fab")
		)
		(fp_line
			(start 0.67945 -0.3048)
			(end 0.67945 0.3048)
			(stroke
				(width 0.1)
				(type default)
			)
			(layer "F.Fab")
		)
		(fp_line
			(start 0.67945 0.3048)
			(end 0.120396 0.3048)
			(stroke
				(width 0.1)
				(type default)
			)
			(layer "F.Fab")
		)
		(pad "1" smd circle
			(at -0.40005 0)
			(size 0 0)
			(layers "F.Cu" "F.Mask" "F.Paste")
			(net "P3V3_AUX")
		)
		(pad "2" smd circle
			(at 0.40005 0)
			(size 0 0)
			(layers "F.Cu" "F.Mask" "F.Paste")
			(net "GND")
		)
	)
	(footprint ""
		(layer "F.Cu")
		(at 134.643114 -408.517344 -90)
		(property "Reference" "C1525"
			(at 0 0 270)
			(layer "F.SilkS")
			(hide yes)
			(effects
				(font
					(size 1.27 1.27)
				)
			)
		)
		(property "Value" ""
			(at 0 0 270)
			(layer "F.Fab")
			(effects
				(font
					(size 1.27 1.27)
				)
			)
		)
		(duplicate_pad_numbers_are_jumpers no)
		(fp_line
			(start -0.299974 0.150114)
			(end -0.299974 -0.150114)
			(stroke
				(width 0.1)
				(type default)
			)
			(layer "F.Fab")
		)
		(fp_line
			(start 0.299974 0.150114)
			(end -0.299974 0.150114)
			(stroke
				(width 0.1)
				(type default)
			)
			(layer "F.Fab")
		)
		(fp_line
			(start -0.299974 -0.150114)
			(end 0.299974 -0.150114)
			(stroke
				(width 0.1)
				(type default)
			)
			(layer "F.Fab")
		)
		(fp_line
			(start 0.299974 -0.150114)
			(end 0.299974 0.150114)
			(stroke
				(width 0.1)
				(type default)
			)
			(layer "F.Fab")
		)
		(pad "1" smd rect
			(at -0.2667 0 270)
			(size 0.3048 0.381)
			(layers "F.Cu" "F.Mask" "F.Paste")
			(net "P5E_CPU1_PE3_TX_C_DP<11>")
		)
		(pad "2" smd rect
			(at 0.2667 0 270)
			(size 0.3048 0.381)
			(layers "F.Cu" "F.Mask" "F.Paste")
			(net "P5E_CPU1_PE3_TX_DP<11>")
		)
	)
)
